# S9S_MB_2U (Grand Teton) — schematic netlist excerpt (pin names and nets, part order shuffled) for the footprints in the layout excerpt that follows; sources: Cadence DE-HDL packaged netlist, KiCad conversion of 03242023_DA0F0TMBIJ0_F0T_Motherboard_J_brd_V01_OCP.brd

R1268  Q_RES  33.2 1% CHIP  pkg 0402LF  page 183 : A = IRQ_BMC_PCH_NMI_R ; B = IRQ_BMC_PCH_NMI
PR3838  Q_RES  100 1% EMPTY  pkg 0402LF  page 157 : A = P12V_OCP_SFF ; B = P12V_OCP_AVIN_PD_1

(kicad_pcb
	(version 20260206)
	(generator "pcbnew")
	(generator_version "10.0")
	(general
		(thickness 1.6)
		(legacy_teardrops no)
	)
	(paper "A4")
	(title_block
		(title "03242023_DA0F0TMBIJ0_F0T_Motherboard_J_brd_V01_OCP.brd")
		(comment 1 "Grand Teton / footprints 1351-1352 of 6105")
	)
	(layers
		(0 "F.Cu" signal "TOP")
		(4 "In1.Cu" signal "GND")
		(6 "In2.Cu" signal "IN1")
		(8 "In3.Cu" signal "GND1")
		(10 "In4.Cu" signal "IN2")
		(12 "In5.Cu" signal "GND2")
		(14 "In6.Cu" signal "IN3")
		(16 "In7.Cu" signal "GND3")
		(18 "In8.Cu" signal "VCC")
		(20 "In9.Cu" signal "VCC1")
		(22 "In10.Cu" signal "GND4")
		(24 "In11.Cu" signal "IN4")
		(26 "In12.Cu" signal "GND5")
		(28 "In13.Cu" signal "IN5")
		(30 "In14.Cu" signal "GND6")
		(32 "In15.Cu" signal "IN6")
		(34 "In16.Cu" signal "GND7")
		(2 "B.Cu" signal "BOTTOM")
		(9 "F.Adhes" user "F.Adhesive")
		(11 "B.Adhes" user "B.Adhesive")
		(13 "F.Paste" user "Package Geometry/Pastemask Top")
		(15 "B.Paste" user "Package Geometry/Pastemask Bottom")
		(5 "F.SilkS" user "Ref Des/Silkscreen Top")
		(7 "B.SilkS" user "Ref Des/Silkscreen Bottom")
		(1 "F.Mask" user "Board Geometry/Soldermask Top")
		(3 "B.Mask" user "Board Geometry/Soldermask Bottom")
		(17 "Dwgs.User" user "User.Drawings")
		(19 "Cmts.User" user "User.Comments")
		(21 "Eco1.User" user "User.Eco1")
		(23 "Eco2.User" user "User.Eco2")
		(25 "Edge.Cuts" user "Board Geometry/Outline")
		(27 "Margin" user)
		(31 "F.CrtYd" user "Package Geometry/Place Bound Top")
		(29 "B.CrtYd" user "Package Geometry/Place Bound Bottom")
		(35 "F.Fab" user "Ref Des/Assembly Top")
		(33 "B.Fab" user "Ref Des/Assembly Bottom")
	)
	(footprint ""
		(layer "F.Cu")
		(at 440.592972 -22.551898 180)
		(property "Reference" "PR3838"
			(at 0 0 180)
			(layer "F.SilkS")
			(hide yes)
			(effects
				(font
					(size 1.27 1.27)
				)
			)
		)
		(property "Value" ""
			(at 0 0 180)
			(layer "F.Fab")
			(effects
				(font
					(size 1.27 1.27)
				)
			)
		)
		(duplicate_pad_numbers_are_jumpers no)
		(fp_line
			(start 0.7874 0.4064)
			(end -0.7874 0.4064)
			(stroke
				(width 0.1524)
				(type default)
			)
			(layer "F.SilkS")
		)
		(fp_line
			(start 0.7874 -0.4064)
			(end 0.7874 0.4064)
			(stroke
				(width 0.1524)
				(type default)
			)
			(layer "F.SilkS")
		)
		(fp_line
			(start -0.7874 0.4064)
			(end -0.7874 -0.4064)
			(stroke
				(width 0.1524)
				(type default)
			)
			(layer "F.SilkS")
		)
		(fp_line
			(start -0.7874 -0.4064)
			(end 0.7874 -0.4064)
			(stroke
				(width 0.1524)
				(type default)
			)
			(layer "F.SilkS")
		)
		(fp_line
			(start 0.67945 0.3048)
			(end 0.120396 0.3048)
			(stroke
				(width 0.1)
				(type default)
			)
			(layer "F.Fab")
		)
		(fp_line
			(start 0.67945 -0.3048)
			(end 0.67945 0.3048)
			(stroke
				(width 0.1)
				(type default)
			)
			(layer "F.Fab")
		)
		(fp_line
			(start 0.12065 -0.2794)
			(end 0.12065 -0.3048)
			(stroke
				(width 0.1)
				(type default)
			)
			(layer "F.Fab")
		)
		(fp_line
			(start 0.12065 -0.3048)
			(end 0.67945 -0.3048)
			(stroke
				(width 0.1)
				(type default)
			)
			(layer "F.Fab")
		)
		(fp_line
			(start 0.120396 0.3048)
			(end 0.120396 0.2794)
			(stroke
				(width 0.1)
				(type default)
			)
			(layer "F.Fab")
		)
		(fp_line
			(start 0.120396 0.2794)
			(end -0.12065 0.2794)
			(stroke
				(width 0.1)
				(type default)
			)
			(layer "F.Fab")
		)
		(fp_line
			(start -0.12065 0.3048)
			(end -0.67945 0.3048)
			(stroke
				(width 0.1)
				(type default)
			)
			(layer "F.Fab")
		)
		(fp_line
			(start -0.12065 0.2794)
			(end -0.12065 0.3048)
			(stroke
				(width 0.1)
				(type default)
			)
			(layer "F.Fab")
		)
		(fp_line
			(start -0.12065 -0.2794)
			(end 0.12065 -0.2794)
			(stroke
				(width 0.1)
				(type default)
			)
			(layer "F.Fab")
		)
		(fp_line
			(start -0.12065 -0.305054)
			(end -0.12065 -0.2794)
			(stroke
				(width 0.1)
				(type default)
			)
			(layer "F.Fab")
		)
		(fp_line
			(start -0.67945 0.3048)
			(end -0.67945 -0.305054)
			(stroke
				(width 0.1)
				(type default)
			)
			(layer "F.Fab")
		)
		(fp_line
			(start -0.67945 -0.305054)
			(end -0.12065 -0.305054)
			(stroke
				(width 0.1)
				(type default)
			)
			(layer "F.Fab")
		)
		(pad "1" smd circle
			(at -0.40005 0 180)
			(size 0 0)
			(layers "F.Cu" "F.Mask" "F.Paste")
			(net "P12V_OCP_SFF")
		)
		(pad "2" smd circle
			(at 0.40005 0 180)
			(size 0 0)
			(layers "F.Cu" "F.Mask" "F.Paste")
			(net "P12V_OCP_AVIN_PD_1")
		)
	)
	(footprint ""
		(layer "F.Cu")
		(at 329.60691 -20.616926)
		(property "Reference" "R1268"
			(at 0 0 0)
			(layer "F.SilkS")
			(hide yes)
			(effects
				(font
					(size 1.27 1.27)
				)
			)
		)
		(property "Value" ""
			(at 0 0 0)
			(layer "F.Fab")
			(effects
				(font
					(size 1.27 1.27)
				)
			)
		)
		(duplicate_pad_numbers_are_jumpers no)
		(fp_line
			(start -0.7874 -0.4064)
			(end 0.7874 -0.4064)
			(stroke
				(width 0.1524)
				(type default)
			)
			(layer "F.SilkS")
		)
		(fp_line
			(start -0.7874 0.4064)
			(end -0.7874 -0.4064)
			(stroke
				(width 0.1524)
				(type default)
			)
			(layer "F.SilkS")
		)
		(fp_line
			(start 0.7874 -0.4064)
			(end 0.7874 0.4064)
			(stroke
				(width 0.1524)
				(type default)
			)
			(layer "F.SilkS")
		)
		(fp_line
			(start 0.7874 0.4064)
			(end -0.7874 0.4064)
			(stroke
				(width 0.1524)
				(type default)
			)
			(layer "F.SilkS")
		)
		(fp_line
			(start -0.67945 -0.305054)
			(end -0.12065 -0.305054)
			(stroke
				(width 0.1)
				(type default)
			)
			(layer "F.Fab")
		)
		(fp_line
			(start -0.67945 0.3048)
			(end -0.67945 -0.305054)
			(stroke
				(width 0.1)
				(type default)
			)
			(layer "F.Fab")
		)
		(fp_line
			(start -0.12065 -0.305054)
			(end -0.12065 -0.2794)
			(stroke
				(width 0.1)
				(type default)
			)
			(layer "F.Fab")
		)
		(fp_line
			(start -0.12065 -0.2794)
			(end 0.12065 -0.2794)
			(stroke
				(width 0.1)
				(type default)
			)
			(layer "F.Fab")
		)
		(fp_line
			(start -0.12065 0.2794)
			(end -0.12065 0.3048)
			(stroke
				(width 0.1)
				(type default)
			)
			(layer "F.Fab")
		)
		(fp_line
			(start -0.12065 0.3048)
			(end -0.67945 0.3048)
			(stroke
				(width 0.1)
				(type default)
			)
			(layer "F.Fab")
		)
		(fp_line
			(start 0.120396 0.2794)
			(end -0.12065 0.2794)
			(stroke
				(width 0.1)
				(type default)
			)
			(layer "F.Fab")
		)
		(fp_line
			(start 0.120396 0.3048)
			(end 0.120396 0.2794)
			(stroke
				(width 0.1)
				(type default)
			)
			(layer "F.Fab")
		)
		(fp_line
			(start 0.12065 -0.3048)
			(end 0.67945 -0.3048)
			(stroke
				(width 0.1)
				(type default)
			)
			(layer "F.Fab")
		)
		(fp_line
			(start 0.12065 -0.2794)
			(end 0.12065 -0.3048)
			(stroke
				(width 0.1)
				(type default)
			)
			(layer "F.Fab")
		)
		(fp_line
			(start 0.67945 -0.3048)
			(end 0.67945 0.3048)
			(stroke
				(width 0.1)
				(type default)
			)
			(layer "F.Fab")
		)
		(fp_line
			(start 0.67945 0.3048)
			(end 0.120396 0.3048)
			(stroke
				(width 0.1)
				(type default)
			)
			(layer "F.Fab")
		)
		(pad "1" smd circle
			(at -0.40005 0)
			(size 0 0)
			(layers "F.Cu" "F.Mask" "F.Paste")
			(net "IRQ_BMC_PCH_NMI_R")
		)
		(pad "2" smd circle
			(at 0.40005 0)
			(size 0 0)
			(layers "F.Cu" "F.Mask" "F.Paste")
			(net "IRQ_BMC_PCH_NMI")
		)
	)
)
